(kicad_pcb
	(version 20260206)
	(generator "pcbnew")
	(generator_version "10.0")
	(general
		(thickness 1.6)
		(legacy_teardrops no)
	)
	(paper "A4")
	(title_block
		(title "15969-1a.1015WZS0858.brd")
		(comment 1 "Tioga Pass / footprints 67-73 of 295")
	)
	(layers
		(0 "F.Cu" signal "TOP")
		(4 "In1.Cu" signal "L2GND")
		(6 "In2.Cu" signal "L3")
		(8 "In3.Cu" signal "L4")
		(10 "In4.Cu" signal "L5GND")
		(2 "B.Cu" signal "BOTTOM")
		(9 "F.Adhes" user "F.Adhesive")
		(11 "B.Adhes" user "B.Adhesive")
		(13 "F.Paste" user "Package Geometry/Pastemask Top")
		(15 "B.Paste" user "Package Geometry/Pastemask Bottom")
		(5 "F.SilkS" user "Ref Des/Silkscreen Top")
		(7 "B.SilkS" user "Ref Des/Silkscreen Bottom")
		(1 "F.Mask" user "Board Geometry/Soldermask Top")
		(3 "B.Mask" user "Board Geometry/Soldermask Bottom")
		(17 "Dwgs.User" user "User.Drawings")
		(19 "Cmts.User" user "User.Comments")
		(21 "Eco1.User" user "User.Eco1")
		(23 "Eco2.User" user "User.Eco2")
		(25 "Edge.Cuts" user "Board Geometry/Outline")
		(27 "Margin" user)
		(31 "F.CrtYd" user "Package Geometry/Place Bound Top")
		(29 "B.CrtYd" user "Package Geometry/Place Bound Bottom")
		(35 "F.Fab" user "Ref Des/Assembly Top")
		(33 "B.Fab" user "Ref Des/Assembly Bottom")
	)
	(footprint ""
		(layer "F.Cu")
		(at 131.699 -21.971 -90)
		(property "Reference" "R116"
			(at 0 0 270)
			(layer "F.SilkS")
			(hide yes)
			(effects
				(font
					(size 1.27 1.27)
				)
			)
		)
		(property "Value" "10KR2F-2-GP"
			(at 0.064008 -3.993896 270)
			(unlocked yes)
			(layer "F.Fab")
			(hide yes)
			(effects
				(font
					(size 1.016 1.016)
					(thickness 0.1524)
				)
			)
		)
		(property "Device Type" "R402H16"
			(at 0.064008 -5.517896 270)
			(unlocked yes)
			(layer "F.Fab")
			(hide yes)
			(effects
				(font
					(size 1.016 1.016)
					(thickness 0.1524)
				)
			)
		)
		(duplicate_pad_numbers_are_jumpers no)
		(fp_line
			(start -0.508 -0.9398)
			(end -0.508 0.9398)
			(stroke
				(width 0.1524)
				(type default)
			)
			(layer "F.SilkS")
		)
		(fp_line
			(start 0.508 -0.9398)
			(end -0.508 -0.9398)
			(stroke
				(width 0.1524)
				(type default)
			)
			(layer "F.SilkS")
		)
		(fp_rect
			(start -0.508 0.9398)
			(end 0.508 -0.9398)
			(stroke
				(width 0)
				(type default)
			)
			(fill no)
			(layer "F.CrtYd")
		)
		(fp_rect
			(start -0.508 0.9398)
			(end 0.508 -0.9398)
			(stroke
				(width 0)
				(type default)
			)
			(fill no)
			(layer "F.Fab")
		)
		(pad "1" smd custom
			(at 0 -0.4445 270)
			(size 0.1397 0.1397)
			(layers "F.Cu" "F.Mask" "F.Paste")
			(net "P3V3_STBY")
			(options
				(clearance outline)
				(anchor circle)
			)
			(primitives
				(gr_poly
					(pts
						(arc
							(start -0.1778 -0.2794)
							(mid -0.249642 -0.249642)
							(end -0.2794 -0.1778)
						)
						(arc
							(start -0.2794 0.1778)
							(mid -0.249642 0.249642)
							(end -0.1778 0.2794)
						)
						(arc
							(start 0.1778 0.2794)
							(mid 0.249642 0.249642)
							(end 0.2794 0.1778)
						)
						(arc
							(start 0.2794 -0.1778)
							(mid 0.249642 -0.249642)
							(end 0.1778 -0.2794)
						)
					)
					(width 0)
					(fill yes)
				)
			)
		)
		(pad "2" smd custom
			(at 0 0.4445 270)
			(size 0.1397 0.1397)
			(layers "F.Cu" "F.Mask" "F.Paste")
			(net "GPIO_B_EXP_A0")
			(options
				(clearance outline)
				(anchor circle)
			)
			(primitives
				(gr_poly
					(pts
						(arc
							(start -0.1778 -0.2794)
							(mid -0.249642 -0.249642)
							(end -0.2794 -0.1778)
						)
						(arc
							(start -0.2794 0.1778)
							(mid -0.249642 0.249642)
							(end -0.1778 0.2794)
						)
						(arc
							(start 0.1778 0.2794)
							(mid 0.249642 0.249642)
							(end 0.2794 0.1778)
						)
						(arc
							(start 0.2794 -0.1778)
							(mid 0.249642 -0.249642)
							(end 0.1778 -0.2794)
						)
					)
					(width 0)
					(fill yes)
				)
			)
		)
	)
	(footprint ""
		(layer "F.Cu")
		(at 17.10055 -18.89125 135)
		(property "Reference" "R80"
			(at 0 0 135)
			(layer "F.SilkS")
			(hide yes)
			(effects
				(font
					(size 1.27 1.27)
				)
			)
		)
		(property "Value" "10R2F-L-GP"
			(at 0.063939 -3.993984 135)
			(unlocked yes)
			(layer "F.Fab")
			(hide yes)
			(effects
				(font
					(size 1.016 1.016)
					(thickness 0.1524)
				)
			)
		)
		(property "Device Type" "R402H14"
			(at 0.063939 -5.518113 135)
			(unlocked yes)
			(layer "F.Fab")
			(hide yes)
			(effects
				(font
					(size 1.016 1.016)
					(thickness 0.1524)
				)
			)
		)
		(duplicate_pad_numbers_are_jumpers no)
		(fp_line
			(start 0.507923 -0.940053)
			(end -0.507923 -0.940053)
			(stroke
				(width 0.1524)
				(type default)
			)
			(layer "F.SilkS")
		)
		(fp_line
			(start -0.507923 -0.940053)
			(end -0.507923 0.939694)
			(stroke
				(width 0.1524)
				(type default)
			)
			(layer "F.SilkS")
		)
		(fp_poly
			(pts
				(xy -0.507923 -0.939906) (xy 0.508077 -0.939905) (xy 0.508076 0.939694) (xy -0.507923 0.939694)
			)
			(stroke
				(width 0)
				(type default)
			)
			(fill no)
			(layer "F.CrtYd")
		)
		(fp_poly
			(pts
				(xy -0.507923 -0.939906) (xy 0.508077 -0.939905) (xy 0.508076 0.939694) (xy -0.507923 0.939694)
			)
			(stroke
				(width 0)
				(type default)
			)
			(fill no)
			(layer "F.Fab")
		)
		(pad "1" smd custom
			(at 0 -0.4445 135)
			(size 0.1397 0.1397)
			(layers "F.Cu" "F.Mask" "F.Paste")
			(net "P12V")
			(options
				(clearance outline)
				(anchor circle)
			)
			(primitives
				(gr_poly
					(pts
						(arc
							(start -0.1778 -0.2794)
							(mid -0.249642 -0.249642)
							(end -0.2794 -0.1778)
						)
						(arc
							(start -0.2794 0.1778)
							(mid -0.249642 0.249642)
							(end -0.1778 0.2794)
						)
						(arc
							(start 0.1778 0.2794)
							(mid 0.249642 0.249642)
							(end 0.2794 0.1778)
						)
						(arc
							(start 0.2794 -0.1778)
							(mid 0.249642 -0.249642)
							(end 0.1778 -0.2794)
						)
					)
					(width 0)
					(fill yes)
				)
			)
		)
		(pad "2" smd custom
			(at 0 0.4445 135)
			(size 0.1397 0.1397)
			(layers "F.Cu" "F.Mask" "F.Paste")
			(net "SLOT2_P12V_SENSE_VP_R")
			(options
				(clearance outline)
				(anchor circle)
			)
			(primitives
				(gr_poly
					(pts
						(arc
							(start -0.1778 -0.2794)
							(mid -0.249642 -0.249642)
							(end -0.2794 -0.1778)
						)
						(arc
							(start -0.2794 0.1778)
							(mid -0.249642 0.249642)
							(end -0.1778 0.2794)
						)
						(arc
							(start 0.1778 0.2794)
							(mid 0.249642 0.249642)
							(end 0.2794 0.1778)
						)
						(arc
							(start 0.2794 -0.1778)
							(mid 0.249642 -0.249642)
							(end 0.1778 -0.2794)
						)
					)
					(width 0)
					(fill yes)
				)
			)
		)
	)
	(footprint ""
		(layer "F.Cu")
		(at 96.647 -16.8656)
		(property "Reference" "R73"
			(at 0 0 0)
			(layer "F.SilkS")
			(hide yes)
			(effects
				(font
					(size 1.27 1.27)
				)
			)
		)
		(property "Value" "0R2F-1-GP"
			(at 0.064008 -3.993896 0)
			(unlocked yes)
			(layer "F.Fab")
			(hide yes)
			(effects
				(font
					(size 1.016 1.016)
					(thickness 0.1524)
				)
			)
		)
		(property "Device Type" "R402H16"
			(at 0.064008 -5.517896 0)
			(unlocked yes)
			(layer "F.Fab")
			(hide yes)
			(effects
				(font
					(size 1.016 1.016)
					(thickness 0.1524)
				)
			)
		)
		(duplicate_pad_numbers_are_jumpers no)
		(fp_line
			(start -0.508 -0.9398)
			(end -0.508 0.9398)
			(stroke
				(width 0.1524)
				(type default)
			)
			(layer "F.SilkS")
		)
		(fp_line
			(start 0.508 -0.9398)
			(end -0.508 -0.9398)
			(stroke
				(width 0.1524)
				(type default)
			)
			(layer "F.SilkS")
		)
		(fp_rect
			(start -0.508 0.9398)
			(end 0.508 -0.9398)
			(stroke
				(width 0)
				(type default)
			)
			(fill no)
			(layer "F.CrtYd")
		)
		(fp_rect
			(start -0.508 0.9398)
			(end 0.508 -0.9398)
			(stroke
				(width 0)
				(type default)
			)
			(fill no)
			(layer "F.Fab")
		)
		(pad "1" smd custom
			(at 0 -0.4445)
			(size 0.1397 0.1397)
			(layers "F.Cu" "F.Mask" "F.Paste")
			(net "PERST_SLOT_N")
			(options
				(clearance outline)
				(anchor circle)
			)
			(primitives
				(gr_poly
					(pts
						(arc
							(start -0.1778 -0.2794)
							(mid -0.249642 -0.249642)
							(end -0.2794 -0.1778)
						)
						(arc
							(start -0.2794 0.1778)
							(mid -0.249642 0.249642)
							(end -0.1778 0.2794)
						)
						(arc
							(start 0.1778 0.2794)
							(mid 0.249642 0.249642)
							(end 0.2794 0.1778)
						)
						(arc
							(start 0.2794 -0.1778)
							(mid 0.249642 -0.249642)
							(end 0.1778 -0.2794)
						)
					)
					(width 0)
					(fill yes)
				)
			)
		)
		(pad "2" smd custom
			(at 0 0.4445)
			(size 0.1397 0.1397)
			(layers "F.Cu" "F.Mask" "F.Paste")
			(net "USB_RESET_N")
			(options
				(clearance outline)
				(anchor circle)
			)
			(primitives
				(gr_poly
					(pts
						(arc
							(start -0.1778 -0.2794)
							(mid -0.249642 -0.249642)
							(end -0.2794 -0.1778)
						)
						(arc
							(start -0.2794 0.1778)
							(mid -0.249642 0.249642)
							(end -0.1778 0.2794)
						)
						(arc
							(start 0.1778 0.2794)
							(mid 0.249642 0.249642)
							(end 0.2794 0.1778)
						)
						(arc
							(start 0.2794 -0.1778)
							(mid 0.249642 -0.249642)
							(end 0.1778 -0.2794)
						)
					)
					(width 0)
					(fill yes)
				)
			)
		)
	)
	(footprint ""
		(layer "F.Cu")
		(at 123.2916 -22.8346 90)
		(property "Reference" "RU28"
			(at 0 0 90)
			(layer "F.SilkS")
			(hide yes)
			(effects
				(font
					(size 1.27 1.27)
				)
			)
		)
		(property "Value" "10KR2F-2-GP"
			(at 0.064008 -3.993896 90)
			(unlocked yes)
			(layer "F.Fab")
			(hide yes)
			(effects
				(font
					(size 1.016 1.016)
					(thickness 0.1524)
				)
			)
		)
		(property "Device Type" "R402H16"
			(at 0.064008 -5.517896 90)
			(unlocked yes)
			(layer "F.Fab")
			(hide yes)
			(effects
				(font
					(size 1.016 1.016)
					(thickness 0.1524)
				)
			)
		)
		(duplicate_pad_numbers_are_jumpers no)
		(fp_line
			(start 0.508 -0.9398)
			(end -0.508 -0.9398)
			(stroke
				(width 0.1524)
				(type default)
			)
			(layer "F.SilkS")
		)
		(fp_line
			(start -0.508 -0.9398)
			(end -0.508 0.9398)
			(stroke
				(width 0.1524)
				(type default)
			)
			(layer "F.SilkS")
		)
		(fp_rect
			(start -0.508 0.9398)
			(end 0.508 -0.9398)
			(stroke
				(width 0)
				(type default)
			)
			(fill no)
			(layer "F.CrtYd")
		)
		(fp_rect
			(start -0.508 0.9398)
			(end 0.508 -0.9398)
			(stroke
				(width 0)
				(type default)
			)
			(fill no)
			(layer "F.Fab")
		)
		(pad "1" smd custom
			(at 0 -0.4445 90)
			(size 0.1397 0.1397)
			(layers "F.Cu" "F.Mask" "F.Paste")
			(net "SMCLK_USB_HUB_R")
			(options
				(clearance outline)
				(anchor circle)
			)
			(primitives
				(gr_poly
					(pts
						(arc
							(start -0.1778 -0.2794)
							(mid -0.249642 -0.249642)
							(end -0.2794 -0.1778)
						)
						(arc
							(start -0.2794 0.1778)
							(mid -0.249642 0.249642)
							(end -0.1778 0.2794)
						)
						(arc
							(start 0.1778 0.2794)
							(mid 0.249642 0.249642)
							(end 0.2794 0.1778)
						)
						(arc
							(start 0.2794 -0.1778)
							(mid 0.249642 -0.249642)
							(end 0.1778 -0.2794)
						)
					)
					(width 0)
					(fill yes)
				)
			)
		)
		(pad "2" smd custom
			(at 0 0.4445 90)
			(size 0.1397 0.1397)
			(layers "F.Cu" "F.Mask" "F.Paste")
			(net "GND")
			(options
				(clearance outline)
				(anchor circle)
			)
			(primitives
				(gr_poly
					(pts
						(arc
							(start -0.1778 -0.2794)
							(mid -0.249642 -0.249642)
							(end -0.2794 -0.1778)
						)
						(arc
							(start -0.2794 0.1778)
							(mid -0.249642 0.249642)
							(end -0.1778 0.2794)
						)
						(arc
							(start 0.1778 0.2794)
							(mid 0.249642 0.249642)
							(end 0.2794 0.1778)
						)
						(arc
							(start 0.2794 -0.1778)
							(mid 0.249642 -0.249642)
							(end 0.1778 -0.2794)
						)
					)
					(width 0)
					(fill yes)
				)
			)
		)
	)
	(footprint ""
		(layer "F.Cu")
		(at 111.6584 -1.4732 -90)
		(property "Reference" "R58"
			(at 0 0 270)
			(layer "F.SilkS")
			(hide yes)
			(effects
				(font
					(size 1.27 1.27)
				)
			)
		)
		(property "Value" "10KR2F-2-GP"
			(at 0.064008 -3.993896 270)
			(unlocked yes)
			(layer "F.Fab")
			(hide yes)
			(effects
				(font
					(size 1.016 1.016)
					(thickness 0.1524)
				)
			)
		)
		(property "Device Type" "R402H16"
			(at 0.064008 -5.517896 270)
			(unlocked yes)
			(layer "F.Fab")
			(hide yes)
			(effects
				(font
					(size 1.016 1.016)
					(thickness 0.1524)
				)
			)
		)
		(duplicate_pad_numbers_are_jumpers no)
		(fp_line
			(start -0.508 -0.9398)
			(end -0.508 0.9398)
			(stroke
				(width 0.1524)
				(type default)
			)
			(layer "F.SilkS")
		)
		(fp_line
			(start 0.508 -0.9398)
			(end -0.508 -0.9398)
			(stroke
				(width 0.1524)
				(type default)
			)
			(layer "F.SilkS")
		)
		(fp_rect
			(start -0.508 0.9398)
			(end 0.508 -0.9398)
			(stroke
				(width 0)
				(type default)
			)
			(fill no)
			(layer "F.CrtYd")
		)
		(fp_rect
			(start -0.508 0.9398)
			(end 0.508 -0.9398)
			(stroke
				(width 0)
				(type default)
			)
			(fill no)
			(layer "F.Fab")
		)
		(pad "1" smd custom
			(at 0 -0.4445 270)
			(size 0.1397 0.1397)
			(layers "F.Cu" "F.Mask" "F.Paste")
			(net "PU_I2CMUX_INT2_N")
			(options
				(clearance outline)
				(anchor circle)
			)
			(primitives
				(gr_poly
					(pts
						(arc
							(start -0.1778 -0.2794)
							(mid -0.249642 -0.249642)
							(end -0.2794 -0.1778)
						)
						(arc
							(start -0.2794 0.1778)
							(mid -0.249642 0.249642)
							(end -0.1778 0.2794)
						)
						(arc
							(start 0.1778 0.2794)
							(mid 0.249642 0.249642)
							(end 0.2794 0.1778)
						)
						(arc
							(start 0.2794 -0.1778)
							(mid 0.249642 -0.249642)
							(end 0.1778 -0.2794)
						)
					)
					(width 0)
					(fill yes)
				)
			)
		)
		(pad "2" smd custom
			(at 0 0.4445 270)
			(size 0.1397 0.1397)
			(layers "F.Cu" "F.Mask" "F.Paste")
			(net "P3V3_STBY")
			(options
				(clearance outline)
				(anchor circle)
			)
			(primitives
				(gr_poly
					(pts
						(arc
							(start -0.1778 -0.2794)
							(mid -0.249642 -0.249642)
							(end -0.2794 -0.1778)
						)
						(arc
							(start -0.2794 0.1778)
							(mid -0.249642 0.249642)
							(end -0.1778 0.2794)
						)
						(arc
							(start 0.1778 0.2794)
							(mid 0.249642 0.249642)
							(end 0.2794 0.1778)
						)
						(arc
							(start 0.2794 -0.1778)
							(mid 0.249642 -0.249642)
							(end 0.1778 -0.2794)
						)
					)
					(width 0)
					(fill yes)
				)
			)
		)
	)
	(footprint ""
		(layer "F.Cu")
		(at 101.219 -21.6916)
		(property "Reference" "R79"
			(at 0 0 0)
			(layer "F.SilkS")
			(hide yes)
			(effects
				(font
					(size 1.27 1.27)
				)
			)
		)
		(property "Value" "4K7R2F-GP"
			(at 0.064008 -3.993896 0)
			(unlocked yes)
			(layer "F.Fab")
			(hide yes)
			(effects
				(font
					(size 1.016 1.016)
					(thickness 0.1524)
				)
			)
		)
		(property "Device Type" "R402H16"
			(at 0.064008 -5.517896 0)
			(unlocked yes)
			(layer "F.Fab")
			(hide yes)
			(effects
				(font
					(size 1.016 1.016)
					(thickness 0.1524)
				)
			)
		)
		(duplicate_pad_numbers_are_jumpers no)
		(fp_line
			(start -0.508 -0.9398)
			(end -0.508 0.9398)
			(stroke
				(width 0.1524)
				(type default)
			)
			(layer "F.SilkS")
		)
		(fp_line
			(start 0.508 -0.9398)
			(end -0.508 -0.9398)
			(stroke
				(width 0.1524)
				(type default)
			)
			(layer "F.SilkS")
		)
		(fp_rect
			(start -0.508 0.9398)
			(end 0.508 -0.9398)
			(stroke
				(width 0)
				(type default)
			)
			(fill no)
			(layer "F.CrtYd")
		)
		(fp_rect
			(start -0.508 0.9398)
			(end 0.508 -0.9398)
			(stroke
				(width 0)
				(type default)
			)
			(fill no)
			(layer "F.Fab")
		)
		(pad "1" smd custom
			(at 0 -0.4445)
			(size 0.1397 0.1397)
			(layers "F.Cu" "F.Mask" "F.Paste")
			(net "P3V3")
			(options
				(clearance outline)
				(anchor circle)
			)
			(primitives
				(gr_poly
					(pts
						(arc
							(start -0.1778 -0.2794)
							(mid -0.249642 -0.249642)
							(end -0.2794 -0.1778)
						)
						(arc
							(start -0.2794 0.1778)
							(mid -0.249642 0.249642)
							(end -0.1778 0.2794)
						)
						(arc
							(start 0.1778 0.2794)
							(mid 0.249642 0.249642)
							(end 0.2794 0.1778)
						)
						(arc
							(start 0.2794 -0.1778)
							(mid 0.249642 -0.249642)
							(end 0.1778 -0.2794)
						)
					)
					(width 0)
					(fill yes)
				)
			)
		)
		(pad "2" smd custom
			(at 0 0.4445)
			(size 0.1397 0.1397)
			(layers "F.Cu" "F.Mask" "F.Paste")
			(net "RESET_O_2_R")
			(options
				(clearance outline)
				(anchor circle)
			)
			(primitives
				(gr_poly
					(pts
						(arc
							(start -0.1778 -0.2794)
							(mid -0.249642 -0.249642)
							(end -0.2794 -0.1778)
						)
						(arc
							(start -0.2794 0.1778)
							(mid -0.249642 0.249642)
							(end -0.1778 0.2794)
						)
						(arc
							(start 0.1778 0.2794)
							(mid 0.249642 0.249642)
							(end 0.2794 0.1778)
						)
						(arc
							(start 0.2794 -0.1778)
							(mid 0.249642 -0.249642)
							(end 0.1778 -0.2794)
						)
					)
					(width 0)
					(fill yes)
				)
			)
		)
	)
	(footprint ""
		(layer "F.Cu")
		(at 130.5814 1.9812 -90)
		(property "Reference" "R25"
			(at 0 0 270)
			(layer "F.SilkS")
			(hide yes)
			(effects
				(font
					(size 1.27 1.27)
				)
			)
		)
		(property "Value" "4K7R2F-GP"
			(at 0.064008 -3.993896 270)
			(unlocked yes)
			(layer "F.Fab")
			(hide yes)
			(effects
				(font
					(size 1.016 1.016)
					(thickness 0.1524)
				)
			)
		)
		(property "Device Type" "R402H16"
			(at 0.064008 -5.517896 270)
			(unlocked yes)
			(layer "F.Fab")
			(hide yes)
			(effects
				(font
					(size 1.016 1.016)
					(thickness 0.1524)
				)
			)
		)
		(duplicate_pad_numbers_are_jumpers no)
		(fp_line
			(start -0.508 -0.9398)
			(end -0.508 0.9398)
			(stroke
				(width 0.1524)
				(type default)
			)
			(layer "F.SilkS")
		)
		(fp_line
			(start 0.508 -0.9398)
			(end -0.508 -0.9398)
			(stroke
				(width 0.1524)
				(type default)
			)
			(layer "F.SilkS")
		)
		(fp_rect
			(start -0.508 0.9398)
			(end 0.508 -0.9398)
			(stroke
				(width 0)
				(type default)
			)
			(fill no)
			(layer "F.CrtYd")
		)
		(fp_rect
			(start -0.508 0.9398)
			(end 0.508 -0.9398)
			(stroke
				(width 0)
				(type default)
			)
			(fill no)
			(layer "F.Fab")
		)
		(pad "1" smd custom
			(at 0 -0.4445 270)
			(size 0.1397 0.1397)
			(layers "F.Cu" "F.Mask" "F.Paste")
			(net "P3V3_STBY")
			(options
				(clearance outline)
				(anchor circle)
			)
			(primitives
				(gr_poly
					(pts
						(arc
							(start -0.1778 -0.2794)
							(mid -0.249642 -0.249642)
							(end -0.2794 -0.1778)
						)
						(arc
							(start -0.2794 0.1778)
							(mid -0.249642 0.249642)
							(end -0.1778 0.2794)
						)
						(arc
							(start 0.1778 0.2794)
							(mid 0.249642 0.249642)
							(end 0.2794 0.1778)
						)
						(arc
							(start 0.2794 -0.1778)
							(mid 0.249642 -0.249642)
							(end 0.1778 -0.2794)
						)
					)
					(width 0)
					(fill yes)
				)
			)
		)
		(pad "2" smd custom
			(at 0 0.4445 270)
			(size 0.1397 0.1397)
			(layers "F.Cu" "F.Mask" "F.Paste")
			(net "SMDAT_PCH_DEVICE")
			(options
				(clearance outline)
				(anchor circle)
			)
			(primitives
				(gr_poly
					(pts
						(arc
							(start -0.1778 -0.2794)
							(mid -0.249642 -0.249642)
							(end -0.2794 -0.1778)
						)
						(arc
							(start -0.2794 0.1778)
							(mid -0.249642 0.249642)
							(end -0.1778 0.2794)
						)
						(arc
							(start 0.1778 0.2794)
							(mid 0.249642 0.249642)
							(end 0.2794 0.1778)
						)
						(arc
							(start 0.2794 -0.1778)
							(mid 0.249642 -0.249642)
							(end 0.1778 -0.2794)
						)
					)
					(width 0)
					(fill yes)
				)
			)
		)
	)
)
